(kicad_pcb
	(version 20260206)
	(generator "pcbnew")
	(generator_version "10.0")
	(general
		(thickness 1.6)
		(legacy_teardrops no)
	)
	(paper "A4")
	(title_block
		(title "04192023_DAF0TMB3IC0_F0TG_MB_C_brd_V02_OCP.brd")
		(comment 1 "Grand Teton / footprints 4347-4352 of 8354")
	)
	(layers
		(0 "F.Cu" signal "TOP")
		(4 "In1.Cu" signal "GND")
		(6 "In2.Cu" signal "IN1")
		(8 "In3.Cu" signal "GND1")
		(10 "In4.Cu" signal "IN2")
		(12 "In5.Cu" signal "GND2")
		(14 "In6.Cu" signal "IN3")
		(16 "In7.Cu" signal "GND3")
		(18 "In8.Cu" signal "VCC")
		(20 "In9.Cu" signal "VCC1")
		(22 "In10.Cu" signal "GND4")
		(24 "In11.Cu" signal "IN4")
		(26 "In12.Cu" signal "GND5")
		(28 "In13.Cu" signal "IN5")
		(30 "In14.Cu" signal "GND6")
		(32 "In15.Cu" signal "IN6")
		(34 "In16.Cu" signal "GND7")
		(2 "B.Cu" signal "BOTTOM")
		(9 "F.Adhes" user "F.Adhesive")
		(11 "B.Adhes" user "B.Adhesive")
		(13 "F.Paste" user "Package Geometry/Pastemask Top")
		(15 "B.Paste" user "Package Geometry/Pastemask Bottom")
		(5 "F.SilkS" user "Ref Des/Silkscreen Top")
		(7 "B.SilkS" user "Ref Des/Silkscreen Bottom")
		(1 "F.Mask" user "Board Geometry/Soldermask Top")
		(3 "B.Mask" user "Board Geometry/Soldermask Bottom")
		(17 "Dwgs.User" user "User.Drawings")
		(19 "Cmts.User" user "User.Comments")
		(21 "Eco1.User" user "User.Eco1")
		(23 "Eco2.User" user "User.Eco2")
		(25 "Edge.Cuts" user "Board Geometry/Outline")
		(27 "Margin" user)
		(31 "F.CrtYd" user "Package Geometry/Place Bound Top")
		(29 "B.CrtYd" user "Package Geometry/Place Bound Bottom")
		(35 "F.Fab" user "Ref Des/Assembly Top")
		(33 "B.Fab" user "Ref Des/Assembly Bottom")
	)
	(footprint ""
		(layer "F.Cu")
		(at 426.469556 -396.145004 180)
		(property "Reference" "R1045"
			(at 0 0 180)
			(layer "F.SilkS")
			(hide yes)
			(effects
				(font
					(size 1.27 1.27)
				)
			)
		)
		(property "Value" ""
			(at 0 0 180)
			(layer "F.Fab")
			(effects
				(font
					(size 1.27 1.27)
				)
			)
		)
		(duplicate_pad_numbers_are_jumpers no)
		(fp_line
			(start 0.7874 0.4064)
			(end -0.7874 0.4064)
			(stroke
				(width 0.1524)
				(type default)
			)
			(layer "F.SilkS")
		)
		(fp_line
			(start 0.7874 -0.4064)
			(end 0.7874 0.4064)
			(stroke
				(width 0.1524)
				(type default)
			)
			(layer "F.SilkS")
		)
		(fp_line
			(start -0.7874 0.4064)
			(end -0.7874 -0.4064)
			(stroke
				(width 0.1524)
				(type default)
			)
			(layer "F.SilkS")
		)
		(fp_line
			(start -0.7874 -0.4064)
			(end 0.7874 -0.4064)
			(stroke
				(width 0.1524)
				(type default)
			)
			(layer "F.SilkS")
		)
		(fp_line
			(start 0.67945 0.3048)
			(end 0.120396 0.3048)
			(stroke
				(width 0.1)
				(type default)
			)
			(layer "F.Fab")
		)
		(fp_line
			(start 0.67945 -0.3048)
			(end 0.67945 0.3048)
			(stroke
				(width 0.1)
				(type default)
			)
			(layer "F.Fab")
		)
		(fp_line
			(start 0.12065 -0.2794)
			(end 0.12065 -0.3048)
			(stroke
				(width 0.1)
				(type default)
			)
			(layer "F.Fab")
		)
		(fp_line
			(start 0.12065 -0.3048)
			(end 0.67945 -0.3048)
			(stroke
				(width 0.1)
				(type default)
			)
			(layer "F.Fab")
		)
		(fp_line
			(start 0.120396 0.3048)
			(end 0.120396 0.2794)
			(stroke
				(width 0.1)
				(type default)
			)
			(layer "F.Fab")
		)
		(fp_line
			(start 0.120396 0.2794)
			(end -0.12065 0.2794)
			(stroke
				(width 0.1)
				(type default)
			)
			(layer "F.Fab")
		)
		(fp_line
			(start -0.12065 0.3048)
			(end -0.67945 0.3048)
			(stroke
				(width 0.1)
				(type default)
			)
			(layer "F.Fab")
		)
		(fp_line
			(start -0.12065 0.2794)
			(end -0.12065 0.3048)
			(stroke
				(width 0.1)
				(type default)
			)
			(layer "F.Fab")
		)
		(fp_line
			(start -0.12065 -0.2794)
			(end 0.12065 -0.2794)
			(stroke
				(width 0.1)
				(type default)
			)
			(layer "F.Fab")
		)
		(fp_line
			(start -0.12065 -0.305054)
			(end -0.12065 -0.2794)
			(stroke
				(width 0.1)
				(type default)
			)
			(layer "F.Fab")
		)
		(fp_line
			(start -0.67945 0.3048)
			(end -0.67945 -0.305054)
			(stroke
				(width 0.1)
				(type default)
			)
			(layer "F.Fab")
		)
		(fp_line
			(start -0.67945 -0.305054)
			(end -0.12065 -0.305054)
			(stroke
				(width 0.1)
				(type default)
			)
			(layer "F.Fab")
		)
		(pad "1" smd rect
			(at -0.40005 0)
			(size 0.4572 0.508)
			(layers "F.Cu" "F.Mask" "F.Paste")
			(net "P1V8_CPU0_RT2_1A_1D")
		)
		(pad "2" smd rect
			(at 0.40005 0)
			(size 0.4572 0.508)
			(layers "F.Cu" "F.Mask" "F.Paste")
			(net "P1V8_CPU0_RT2_1A")
		)
	)
	(footprint ""
		(layer "F.Cu")
		(at 418.212778 -163.769548 90)
		(property "Reference" "PC607_SOP0_3"
			(at 0 0 90)
			(layer "F.SilkS")
			(hide yes)
			(effects
				(font
					(size 1.27 1.27)
				)
			)
		)
		(property "Value" ""
			(at 0 0 90)
			(layer "F.Fab")
			(effects
				(font
					(size 1.27 1.27)
				)
			)
		)
		(duplicate_pad_numbers_are_jumpers no)
		(fp_line
			(start 0.7874 -0.4064)
			(end 0.7874 0.4064)
			(stroke
				(width 0.1524)
				(type default)
			)
			(layer "F.SilkS")
		)
		(fp_line
			(start -0.7874 -0.4064)
			(end 0.7874 -0.4064)
			(stroke
				(width 0.1524)
				(type default)
			)
			(layer "F.SilkS")
		)
		(fp_line
			(start 0.7874 0.4064)
			(end -0.7874 0.4064)
			(stroke
				(width 0.1524)
				(type default)
			)
			(layer "F.SilkS")
		)
		(fp_line
			(start -0.7874 0.4064)
			(end -0.7874 -0.4064)
			(stroke
				(width 0.1524)
				(type default)
			)
			(layer "F.SilkS")
		)
		(fp_line
			(start -0.12065 -0.305054)
			(end -0.12065 -0.2794)
			(stroke
				(width 0.1)
				(type default)
			)
			(layer "F.Fab")
		)
		(fp_line
			(start -0.67945 -0.305054)
			(end -0.12065 -0.305054)
			(stroke
				(width 0.1)
				(type default)
			)
			(layer "F.Fab")
		)
		(fp_line
			(start 0.67945 -0.3048)
			(end 0.67945 0.3048)
			(stroke
				(width 0.1)
				(type default)
			)
			(layer "F.Fab")
		)
		(fp_line
			(start 0.12065 -0.3048)
			(end 0.67945 -0.3048)
			(stroke
				(width 0.1)
				(type default)
			)
			(layer "F.Fab")
		)
		(fp_line
			(start 0.12065 -0.2794)
			(end 0.12065 -0.3048)
			(stroke
				(width 0.1)
				(type default)
			)
			(layer "F.Fab")
		)
		(fp_line
			(start -0.12065 -0.2794)
			(end 0.12065 -0.2794)
			(stroke
				(width 0.1)
				(type default)
			)
			(layer "F.Fab")
		)
		(fp_line
			(start 0.120396 0.2794)
			(end -0.12065 0.2794)
			(stroke
				(width 0.1)
				(type default)
			)
			(layer "F.Fab")
		)
		(fp_line
			(start -0.12065 0.2794)
			(end -0.12065 0.3048)
			(stroke
				(width 0.1)
				(type default)
			)
			(layer "F.Fab")
		)
		(fp_line
			(start 0.67945 0.3048)
			(end 0.120396 0.3048)
			(stroke
				(width 0.1)
				(type default)
			)
			(layer "F.Fab")
		)
		(fp_line
			(start 0.120396 0.3048)
			(end 0.120396 0.2794)
			(stroke
				(width 0.1)
				(type default)
			)
			(layer "F.Fab")
		)
		(fp_line
			(start -0.12065 0.3048)
			(end -0.67945 0.3048)
			(stroke
				(width 0.1)
				(type default)
			)
			(layer "F.Fab")
		)
		(fp_line
			(start -0.67945 0.3048)
			(end -0.67945 -0.305054)
			(stroke
				(width 0.1)
				(type default)
			)
			(layer "F.Fab")
		)
		(pad "1" smd circle
			(at -0.40005 0 90)
			(size 0 0)
			(layers "F.Cu" "F.Mask" "F.Paste")
			(net "PVDDCR_CPU0_P0_PVCC")
		)
		(pad "2" smd circle
			(at 0.40005 0 90)
			(size 0 0)
			(layers "F.Cu" "F.Mask" "F.Paste")
			(net "GND")
		)
	)
	(footprint ""
		(layer "F.Cu")
		(at 110.15599 -23.534878 -90)
		(property "Reference" "R6332"
			(at 0 0 270)
			(layer "F.SilkS")
			(hide yes)
			(effects
				(font
					(size 1.27 1.27)
				)
			)
		)
		(property "Value" ""
			(at 0 0 270)
			(layer "F.Fab")
			(effects
				(font
					(size 1.27 1.27)
				)
			)
		)
		(duplicate_pad_numbers_are_jumpers no)
		(fp_line
			(start -0.7874 0.4064)
			(end -0.7874 -0.4064)
			(stroke
				(width 0.1524)
				(type default)
			)
			(layer "F.SilkS")
		)
		(fp_line
			(start 0.7874 0.4064)
			(end -0.7874 0.4064)
			(stroke
				(width 0.1524)
				(type default)
			)
			(layer "F.SilkS")
		)
		(fp_line
			(start -0.7874 -0.4064)
			(end 0.7874 -0.4064)
			(stroke
				(width 0.1524)
				(type default)
			)
			(layer "F.SilkS")
		)
		(fp_line
			(start 0.7874 -0.4064)
			(end 0.7874 0.4064)
			(stroke
				(width 0.1524)
				(type default)
			)
			(layer "F.SilkS")
		)
		(fp_line
			(start -0.67945 0.3048)
			(end -0.67945 -0.305054)
			(stroke
				(width 0.1)
				(type default)
			)
			(layer "F.Fab")
		)
		(fp_line
			(start -0.12065 0.3048)
			(end -0.67945 0.3048)
			(stroke
				(width 0.1)
				(type default)
			)
			(layer "F.Fab")
		)
		(fp_line
			(start 0.120396 0.3048)
			(end 0.120396 0.2794)
			(stroke
				(width 0.1)
				(type default)
			)
			(layer "F.Fab")
		)
		(fp_line
			(start 0.67945 0.3048)
			(end 0.120396 0.3048)
			(stroke
				(width 0.1)
				(type default)
			)
			(layer "F.Fab")
		)
		(fp_line
			(start -0.12065 0.2794)
			(end -0.12065 0.3048)
			(stroke
				(width 0.1)
				(type default)
			)
			(layer "F.Fab")
		)
		(fp_line
			(start 0.120396 0.2794)
			(end -0.12065 0.2794)
			(stroke
				(width 0.1)
				(type default)
			)
			(layer "F.Fab")
		)
		(fp_line
			(start -0.12065 -0.2794)
			(end 0.12065 -0.2794)
			(stroke
				(width 0.1)
				(type default)
			)
			(layer "F.Fab")
		)
		(fp_line
			(start 0.12065 -0.2794)
			(end 0.12065 -0.3048)
			(stroke
				(width 0.1)
				(type default)
			)
			(layer "F.Fab")
		)
		(fp_line
			(start 0.12065 -0.3048)
			(end 0.67945 -0.3048)
			(stroke
				(width 0.1)
				(type default)
			)
			(layer "F.Fab")
		)
		(fp_line
			(start 0.67945 -0.3048)
			(end 0.67945 0.3048)
			(stroke
				(width 0.1)
				(type default)
			)
			(layer "F.Fab")
		)
		(fp_line
			(start -0.67945 -0.305054)
			(end -0.12065 -0.305054)
			(stroke
				(width 0.1)
				(type default)
			)
			(layer "F.Fab")
		)
		(fp_line
			(start -0.12065 -0.305054)
			(end -0.12065 -0.2794)
			(stroke
				(width 0.1)
				(type default)
			)
			(layer "F.Fab")
		)
		(pad "1" smd circle
			(at -0.40005 0 270)
			(size 0 0)
			(layers "F.Cu" "F.Mask" "F.Paste")
			(net "USB_HUB2_TI_USB_R1_MRP_RBIAS")
		)
		(pad "2" smd circle
			(at 0.40005 0 270)
			(size 0 0)
			(layers "F.Cu" "F.Mask" "F.Paste")
			(net "GND")
		)
	)
	(footprint ""
		(layer "F.Cu")
		(at 66.929 -56.261)
		(property "Reference" "R1176"
			(at 0 0 0)
			(layer "F.SilkS")
			(hide yes)
			(effects
				(font
					(size 1.27 1.27)
				)
			)
		)
		(property "Value" ""
			(at 0 0 0)
			(layer "F.Fab")
			(effects
				(font
					(size 1.27 1.27)
				)
			)
		)
		(duplicate_pad_numbers_are_jumpers no)
		(fp_line
			(start -0.7874 -0.4064)
			(end 0.7874 -0.4064)
			(stroke
				(width 0.1524)
				(type default)
			)
			(layer "F.SilkS")
		)
		(fp_line
			(start -0.7874 0.4064)
			(end -0.7874 -0.4064)
			(stroke
				(width 0.1524)
				(type default)
			)
			(layer "F.SilkS")
		)
		(fp_line
			(start 0.7874 -0.4064)
			(end 0.7874 0.4064)
			(stroke
				(width 0.1524)
				(type default)
			)
			(layer "F.SilkS")
		)
		(fp_line
			(start 0.7874 0.4064)
			(end -0.7874 0.4064)
			(stroke
				(width 0.1524)
				(type default)
			)
			(layer "F.SilkS")
		)
		(fp_line
			(start -0.67945 -0.305054)
			(end -0.12065 -0.305054)
			(stroke
				(width 0.1)
				(type default)
			)
			(layer "F.Fab")
		)
		(fp_line
			(start -0.67945 0.3048)
			(end -0.67945 -0.305054)
			(stroke
				(width 0.1)
				(type default)
			)
			(layer "F.Fab")
		)
		(fp_line
			(start -0.12065 -0.305054)
			(end -0.12065 -0.2794)
			(stroke
				(width 0.1)
				(type default)
			)
			(layer "F.Fab")
		)
		(fp_line
			(start -0.12065 -0.2794)
			(end 0.12065 -0.2794)
			(stroke
				(width 0.1)
				(type default)
			)
			(layer "F.Fab")
		)
		(fp_line
			(start -0.12065 0.2794)
			(end -0.12065 0.3048)
			(stroke
				(width 0.1)
				(type default)
			)
			(layer "F.Fab")
		)
		(fp_line
			(start -0.12065 0.3048)
			(end -0.67945 0.3048)
			(stroke
				(width 0.1)
				(type default)
			)
			(layer "F.Fab")
		)
		(fp_line
			(start 0.120396 0.2794)
			(end -0.12065 0.2794)
			(stroke
				(width 0.1)
				(type default)
			)
			(layer "F.Fab")
		)
		(fp_line
			(start 0.120396 0.3048)
			(end 0.120396 0.2794)
			(stroke
				(width 0.1)
				(type default)
			)
			(layer "F.Fab")
		)
		(fp_line
			(start 0.12065 -0.3048)
			(end 0.67945 -0.3048)
			(stroke
				(width 0.1)
				(type default)
			)
			(layer "F.Fab")
		)
		(fp_line
			(start 0.12065 -0.2794)
			(end 0.12065 -0.3048)
			(stroke
				(width 0.1)
				(type default)
			)
			(layer "F.Fab")
		)
		(fp_line
			(start 0.67945 -0.3048)
			(end 0.67945 0.3048)
			(stroke
				(width 0.1)
				(type default)
			)
			(layer "F.Fab")
		)
		(fp_line
			(start 0.67945 0.3048)
			(end 0.120396 0.3048)
			(stroke
				(width 0.1)
				(type default)
			)
			(layer "F.Fab")
		)
		(pad "1" smd circle
			(at -0.40005 0)
			(size 0 0)
			(layers "F.Cu" "F.Mask" "F.Paste")
			(net "P3V3_AUX")
		)
		(pad "2" smd circle
			(at 0.40005 0)
			(size 0 0)
			(layers "F.Cu" "F.Mask" "F.Paste")
			(net "FM_OCP_V3_2_AUX_PWR_R_EN")
		)
	)
	(footprint ""
		(layer "F.Cu")
		(at 423.473372 -424.217846)
		(property "Reference" "C989"
			(at 0 0 0)
			(layer "F.SilkS")
			(hide yes)
			(effects
				(font
					(size 1.27 1.27)
				)
			)
		)
		(property "Value" ""
			(at 0 0 0)
			(layer "F.Fab")
			(effects
				(font
					(size 1.27 1.27)
				)
			)
		)
		(duplicate_pad_numbers_are_jumpers no)
		(fp_line
			(start -0.299974 -0.150114)
			(end 0.299974 -0.150114)
			(stroke
				(width 0.1)
				(type default)
			)
			(layer "F.Fab")
		)
		(fp_line
			(start -0.299974 0.150114)
			(end -0.299974 -0.150114)
			(stroke
				(width 0.1)
				(type default)
			)
			(layer "F.Fab")
		)
		(fp_line
			(start 0.299974 -0.150114)
			(end 0.299974 0.150114)
			(stroke
				(width 0.1)
				(type default)
			)
			(layer "F.Fab")
		)
		(fp_line
			(start 0.299974 0.150114)
			(end -0.299974 0.150114)
			(stroke
				(width 0.1)
				(type default)
			)
			(layer "F.Fab")
		)
		(pad "1" smd rect
			(at -0.2667 0)
			(size 0.3048 0.381)
			(layers "F.Cu" "F.Mask" "F.Paste")
			(net "P1V8_CPU0_RT_1D")
		)
		(pad "2" smd rect
			(at 0.2667 0)
			(size 0.3048 0.381)
			(layers "F.Cu" "F.Mask" "F.Paste")
			(net "GND")
		)
	)
	(footprint ""
		(layer "F.Cu")
		(at 49.796954 -373.03583 -90)
		(property "Reference" "C827"
			(at 0 0 270)
			(layer "F.SilkS")
			(hide yes)
			(effects
				(font
					(size 1.27 1.27)
				)
			)
		)
		(property "Value" ""
			(at 0 0 270)
			(layer "F.Fab")
			(effects
				(font
					(size 1.27 1.27)
				)
			)
		)
		(duplicate_pad_numbers_are_jumpers no)
		(fp_line
			(start -0.299974 0.150114)
			(end -0.299974 -0.150114)
			(stroke
				(width 0.1)
				(type default)
			)
			(layer "F.Fab")
		)
		(fp_line
			(start 0.299974 0.150114)
			(end -0.299974 0.150114)
			(stroke
				(width 0.1)
				(type default)
			)
			(layer "F.Fab")
		)
		(fp_line
			(start -0.299974 -0.150114)
			(end 0.299974 -0.150114)
			(stroke
				(width 0.1)
				(type default)
			)
			(layer "F.Fab")
		)
		(fp_line
			(start 0.299974 -0.150114)
			(end 0.299974 0.150114)
			(stroke
				(width 0.1)
				(type default)
			)
			(layer "F.Fab")
		)
		(pad "1" smd rect
			(at -0.2667 0 270)
			(size 0.3048 0.381)
			(layers "F.Cu" "F.Mask" "F.Paste")
			(net "P5E_CPU1_P0_TX_C_DP<5>")
		)
		(pad "2" smd rect
			(at 0.2667 0 270)
			(size 0.3048 0.381)
			(layers "F.Cu" "F.Mask" "F.Paste")
			(net "P5E_CPU1_P0_TX_DP<5>")
		)
	)
)
